# SCM (Grand Teton) — schematic netlist excerpt (pin names and nets, part order shuffled) for the footprints in the layout excerpt that follows; sources: Cadence DE-HDL packaged netlist, KiCad conversion of 12092022_DA0F0TMDCD0_F0T_Management_Board_D_brd_V3_OCP.brd

R608  Q_RES  4.7K 1% CHIP  pkg 0402LF  page 42 : A = P3V3_AUX ; B = BMC_CPLD_GPIO_13
R637  Q_RES  0 5% CHIP  pkg 0402LF  page 13 : A = RST_WDTRST_PLD_R1_N ; B = RST_WDTRST_PLD_N

(kicad_pcb
	(version 20260206)
	(generator "pcbnew")
	(generator_version "10.0")
	(general
		(thickness 1.6)
		(legacy_teardrops no)
	)
	(paper "A4")
	(title_block
		(title "12092022_DA0F0TMDCD0_F0T_Management_Board_D_brd_V3_OCP.brd")
		(comment 1 "Grand Teton / footprints 1318-1319 of 1440")
	)
	(layers
		(0 "F.Cu" signal "TOP")
		(4 "In1.Cu" signal "GND")
		(6 "In2.Cu" signal "IN1")
		(8 "In3.Cu" signal "GND1")
		(10 "In4.Cu" signal "IN2")
		(12 "In5.Cu" signal "VCC")
		(14 "In6.Cu" signal "VCC1")
		(16 "In7.Cu" signal "IN3")
		(18 "In8.Cu" signal "GND2")
		(20 "In9.Cu" signal "IN4")
		(22 "In10.Cu" signal "GND3")
		(2 "B.Cu" signal "BOTTOM")
		(9 "F.Adhes" user "F.Adhesive")
		(11 "B.Adhes" user "B.Adhesive")
		(13 "F.Paste" user "Package Geometry/Pastemask Top")
		(15 "B.Paste" user "Package Geometry/Pastemask Bottom")
		(5 "F.SilkS" user "Ref Des/Silkscreen Top")
		(7 "B.SilkS" user "Ref Des/Silkscreen Bottom")
		(1 "F.Mask" user "Board Geometry/Soldermask Top")
		(3 "B.Mask" user "Board Geometry/Soldermask Bottom")
		(17 "Dwgs.User" user "User.Drawings")
		(19 "Cmts.User" user "User.Comments")
		(21 "Eco1.User" user "User.Eco1")
		(23 "Eco2.User" user "User.Eco2")
		(25 "Edge.Cuts" user "Board Geometry/Outline")
		(27 "Margin" user)
		(31 "F.CrtYd" user "Package Geometry/Place Bound Top")
		(29 "B.CrtYd" user "Package Geometry/Place Bound Bottom")
		(35 "F.Fab" user "Ref Des/Assembly Top")
		(33 "B.Fab" user "Ref Des/Assembly Bottom")
	)
	(footprint ""
		(layer "B.Cu")
		(at 12.319 -95.504)
		(property "Reference" "R608"
			(at 0 0 0)
			(layer "B.SilkS")
			(hide yes)
			(effects
				(font
					(size 1.27 1.27)
				)
				(justify mirror)
			)
		)
		(property "Value" ""
			(at 0 0 0)
			(layer "B.Fab")
			(effects
				(font
					(size 1.27 1.27)
				)
				(justify mirror)
			)
		)
		(duplicate_pad_numbers_are_jumpers no)
		(fp_line
			(start -0.7874 -0.4064)
			(end -0.7874 0.4064)
			(stroke
				(width 0.1524)
				(type default)
			)
			(layer "B.SilkS")
		)
		(fp_line
			(start -0.7874 0.4064)
			(end 0.7874 0.4064)
			(stroke
				(width 0.1524)
				(type default)
			)
			(layer "B.SilkS")
		)
		(fp_line
			(start 0.7874 -0.4064)
			(end -0.7874 -0.4064)
			(stroke
				(width 0.1524)
				(type default)
			)
			(layer "B.SilkS")
		)
		(fp_line
			(start 0.7874 0.4064)
			(end 0.7874 -0.4064)
			(stroke
				(width 0.1524)
				(type default)
			)
			(layer "B.SilkS")
		)
		(fp_line
			(start -0.67945 -0.3048)
			(end -0.67945 0.3048)
			(stroke
				(width 0.1)
				(type default)
			)
			(layer "B.Fab")
		)
		(fp_line
			(start -0.67945 0.3048)
			(end -0.120396 0.3048)
			(stroke
				(width 0.1)
				(type default)
			)
			(layer "B.Fab")
		)
		(fp_line
			(start -0.12065 -0.3048)
			(end -0.67945 -0.3048)
			(stroke
				(width 0.1)
				(type default)
			)
			(layer "B.Fab")
		)
		(fp_line
			(start -0.12065 -0.2794)
			(end -0.12065 -0.3048)
			(stroke
				(width 0.1)
				(type default)
			)
			(layer "B.Fab")
		)
		(fp_line
			(start -0.120396 0.2794)
			(end 0.12065 0.2794)
			(stroke
				(width 0.1)
				(type default)
			)
			(layer "B.Fab")
		)
		(fp_line
			(start -0.120396 0.3048)
			(end -0.120396 0.2794)
			(stroke
				(width 0.1)
				(type default)
			)
			(layer "B.Fab")
		)
		(fp_line
			(start 0.12065 -0.305054)
			(end 0.12065 -0.2794)
			(stroke
				(width 0.1)
				(type default)
			)
			(layer "B.Fab")
		)
		(fp_line
			(start 0.12065 -0.2794)
			(end -0.12065 -0.2794)
			(stroke
				(width 0.1)
				(type default)
			)
			(layer "B.Fab")
		)
		(fp_line
			(start 0.12065 0.2794)
			(end 0.12065 0.3048)
			(stroke
				(width 0.1)
				(type default)
			)
			(layer "B.Fab")
		)
		(fp_line
			(start 0.12065 0.3048)
			(end 0.67945 0.3048)
			(stroke
				(width 0.1)
				(type default)
			)
			(layer "B.Fab")
		)
		(fp_line
			(start 0.67945 -0.305054)
			(end 0.12065 -0.305054)
			(stroke
				(width 0.1)
				(type default)
			)
			(layer "B.Fab")
		)
		(fp_line
			(start 0.67945 0.3048)
			(end 0.67945 -0.305054)
			(stroke
				(width 0.1)
				(type default)
			)
			(layer "B.Fab")
		)
		(pad "1" smd circle
			(at 0.40005 0 180)
			(size 0 0)
			(layers "B.Cu" "B.Mask" "B.Paste")
			(net "P3V3_AUX")
		)
		(pad "2" smd circle
			(at -0.40005 0 180)
			(size 0 0)
			(layers "B.Cu" "B.Mask" "B.Paste")
			(net "BMC_CPLD_GPIO_13")
		)
	)
	(footprint ""
		(layer "B.Cu")
		(at 55.5752 -64.02324 -90)
		(property "Reference" "R637"
			(at 0 0 90)
			(layer "B.SilkS")
			(hide yes)
			(effects
				(font
					(size 1.27 1.27)
				)
				(justify mirror)
			)
		)
		(property "Value" ""
			(at 0 0 90)
			(layer "B.Fab")
			(effects
				(font
					(size 1.27 1.27)
				)
				(justify mirror)
			)
		)
		(duplicate_pad_numbers_are_jumpers no)
		(fp_line
			(start -0.7874 0.4064)
			(end 0.7874 0.4064)
			(stroke
				(width 0.1524)
				(type default)
			)
			(layer "B.SilkS")
		)
		(fp_line
			(start 0.7874 0.4064)
			(end 0.7874 -0.4064)
			(stroke
				(width 0.1524)
				(type default)
			)
			(layer "B.SilkS")
		)
		(fp_line
			(start -0.7874 -0.4064)
			(end -0.7874 0.4064)
			(stroke
				(width 0.1524)
				(type default)
			)
			(layer "B.SilkS")
		)
		(fp_line
			(start 0.7874 -0.4064)
			(end -0.7874 -0.4064)
			(stroke
				(width 0.1524)
				(type default)
			)
			(layer "B.SilkS")
		)
		(fp_line
			(start -0.67945 0.3048)
			(end -0.120396 0.3048)
			(stroke
				(width 0.1)
				(type default)
			)
			(layer "B.Fab")
		)
		(fp_line
			(start -0.120396 0.3048)
			(end -0.120396 0.2794)
			(stroke
				(width 0.1)
				(type default)
			)
			(layer "B.Fab")
		)
		(fp_line
			(start 0.12065 0.3048)
			(end 0.67945 0.3048)
			(stroke
				(width 0.1)
				(type default)
			)
			(layer "B.Fab")
		)
		(fp_line
			(start 0.67945 0.3048)
			(end 0.67945 -0.305054)
			(stroke
				(width 0.1)
				(type default)
			)
			(layer "B.Fab")
		)
		(fp_line
			(start -0.120396 0.2794)
			(end 0.12065 0.2794)
			(stroke
				(width 0.1)
				(type default)
			)
			(layer "B.Fab")
		)
		(fp_line
			(start 0.12065 0.2794)
			(end 0.12065 0.3048)
			(stroke
				(width 0.1)
				(type default)
			)
			(layer "B.Fab")
		)
		(fp_line
			(start -0.12065 -0.2794)
			(end -0.12065 -0.3048)
			(stroke
				(width 0.1)
				(type default)
			)
			(layer "B.Fab")
		)
		(fp_line
			(start 0.12065 -0.2794)
			(end -0.12065 -0.2794)
			(stroke
				(width 0.1)
				(type default)
			)
			(layer "B.Fab")
		)
		(fp_line
			(start -0.67945 -0.3048)
			(end -0.67945 0.3048)
			(stroke
				(width 0.1)
				(type default)
			)
			(layer "B.Fab")
		)
		(fp_line
			(start -0.12065 -0.3048)
			(end -0.67945 -0.3048)
			(stroke
				(width 0.1)
				(type default)
			)
			(layer "B.Fab")
		)
		(fp_line
			(start 0.12065 -0.305054)
			(end 0.12065 -0.2794)
			(stroke
				(width 0.1)
				(type default)
			)
			(layer "B.Fab")
		)
		(fp_line
			(start 0.67945 -0.305054)
			(end 0.12065 -0.305054)
			(stroke
				(width 0.1)
				(type default)
			)
			(layer "B.Fab")
		)
		(pad "1" smd circle
			(at 0.40005 0 90)
			(size 0 0)
			(layers "B.Cu" "B.Mask" "B.Paste")
			(net "RST_WDTRST_PLD_R1_N")
		)
		(pad "2" smd circle
			(at -0.40005 0 90)
			(size 0 0)
			(layers "B.Cu" "B.Mask" "B.Paste")
			(net "RST_WDTRST_PLD_N")
		)
	)
)
